(kicad_pcb
	(version 20260206)
	(generator "pcbnew")
	(generator_version "10.0")
	(general
		(thickness 1.6)
		(legacy_teardrops no)
	)
	(paper "A4")
	(title_block
		(title "fcb — 12433-1M.1206WZS1330.brd")
		(comment 1 "Open Vault / Knox (Wiwynn) / footprints 93-98 of 495")
	)
	(layers
		(0 "F.Cu" signal "TOP")
		(4 "In1.Cu" signal "L2GND")
		(6 "In2.Cu" signal "L3VCC")
		(2 "B.Cu" signal "BOTTOM")
		(9 "F.Adhes" user "F.Adhesive")
		(11 "B.Adhes" user "B.Adhesive")
		(13 "F.Paste" user "Package Geometry/Pastemask Top")
		(15 "B.Paste" user "Package Geometry/Pastemask Bottom")
		(5 "F.SilkS" user "Ref Des/Silkscreen Top")
		(7 "B.SilkS" user "Ref Des/Silkscreen Bottom")
		(1 "F.Mask" user "Board Geometry/Soldermask Top")
		(3 "B.Mask" user "Board Geometry/Soldermask Bottom")
		(17 "Dwgs.User" user "User.Drawings")
		(19 "Cmts.User" user "User.Comments")
		(21 "Eco1.User" user "User.Eco1")
		(23 "Eco2.User" user "User.Eco2")
		(25 "Edge.Cuts" user "Board Geometry/Outline")
		(27 "Margin" user)
		(31 "F.CrtYd" user "Package Geometry/Place Bound Top")
		(29 "B.CrtYd" user "Package Geometry/Place Bound Bottom")
		(35 "F.Fab" user "Ref Des/Assembly Top")
		(33 "B.Fab" user "Ref Des/Assembly Bottom")
	)
	(footprint ""
		(layer "F.Cu")
		(at 43.019726 -366.069626)
		(property "Reference" "PQ6"
			(at 0 0 0)
			(layer "F.SilkS")
			(hide yes)
			(effects
				(font
					(size 1.27 1.27)
				)
			)
		)
		(property "Value" "PMBS3904-1-GP"
			(at 0 -9.0932 0)
			(unlocked yes)
			(layer "F.Fab")
			(hide yes)
			(effects
				(font
					(size 1.016 1.016)
					(thickness 0.1524)
				)
			)
		)
		(property "Device Type" "SOT-23-10H44"
			(at 0 -10.6172 0)
			(unlocked yes)
			(layer "F.Fab")
			(hide yes)
			(effects
				(font
					(size 1.016 1.016)
					(thickness 0.1524)
				)
			)
		)
		(duplicate_pad_numbers_are_jumpers no)
		(fp_line
			(start -1.7526 1.8796)
			(end -1.7526 0.9906)
			(stroke
				(width 0.3302)
				(type default)
			)
			(layer "F.SilkS")
		)
		(fp_line
			(start -1.651 -1.778)
			(end -1.651 1.778)
			(stroke
				(width 0.1524)
				(type default)
			)
			(layer "F.SilkS")
		)
		(fp_line
			(start -1.651 1.778)
			(end 1.651 1.778)
			(stroke
				(width 0.1524)
				(type default)
			)
			(layer "F.SilkS")
		)
		(fp_line
			(start -1.279398 2.152142)
			(end -0.9906 1.86309)
			(stroke
				(width 0.0127)
				(type default)
			)
			(layer "F.SilkS")
		)
		(fp_line
			(start -1.279144 2.15265)
			(end -0.701294 2.15265)
			(stroke
				(width 0.0127)
				(type default)
			)
			(layer "F.SilkS")
		)
		(fp_line
			(start -1.260856 2.1336)
			(end -0.720344 2.1336)
			(stroke
				(width 0.0127)
				(type default)
			)
			(layer "F.SilkS")
		)
		(fp_line
			(start -1.251458 2.124202)
			(end -0.729996 2.124202)
			(stroke
				(width 0.0127)
				(type default)
			)
			(layer "F.SilkS")
		)
		(fp_line
			(start -1.241806 2.11455)
			(end -0.739394 2.11455)
			(stroke
				(width 0.0127)
				(type default)
			)
			(layer "F.SilkS")
		)
		(fp_line
			(start -1.232408 2.105152)
			(end -0.749046 2.105152)
			(stroke
				(width 0.0127)
				(type default)
			)
			(layer "F.SilkS")
		)
		(fp_line
			(start -1.222756 2.0955)
			(end -0.758444 2.0955)
			(stroke
				(width 0.0127)
				(type default)
			)
			(layer "F.SilkS")
		)
		(fp_line
			(start -1.213358 2.086102)
			(end -0.768096 2.086102)
			(stroke
				(width 0.0127)
				(type default)
			)
			(layer "F.SilkS")
		)
		(fp_line
			(start -1.203706 2.07645)
			(end -0.777494 2.07645)
			(stroke
				(width 0.0127)
				(type default)
			)
			(layer "F.SilkS")
		)
		(fp_line
			(start -1.194308 2.067052)
			(end -0.787146 2.067052)
			(stroke
				(width 0.0127)
				(type default)
			)
			(layer "F.SilkS")
		)
		(fp_line
			(start -1.184656 2.0574)
			(end -0.796544 2.0574)
			(stroke
				(width 0.0127)
				(type default)
			)
			(layer "F.SilkS")
		)
		(fp_line
			(start -1.175258 2.048002)
			(end -0.806196 2.048002)
			(stroke
				(width 0.0127)
				(type default)
			)
			(layer "F.SilkS")
		)
		(fp_line
			(start -1.165606 2.03835)
			(end -0.815594 2.03835)
			(stroke
				(width 0.0127)
				(type default)
			)
			(layer "F.SilkS")
		)
		(fp_line
			(start -1.156208 2.028952)
			(end -0.825246 2.028952)
			(stroke
				(width 0.0127)
				(type default)
			)
			(layer "F.SilkS")
		)
		(fp_line
			(start -1.146556 2.0193)
			(end -0.834644 2.0193)
			(stroke
				(width 0.0127)
				(type default)
			)
			(layer "F.SilkS")
		)
		(fp_line
			(start -1.137158 2.009902)
			(end -0.844296 2.009902)
			(stroke
				(width 0.0127)
				(type default)
			)
			(layer "F.SilkS")
		)
		(fp_line
			(start -1.127506 2.00025)
			(end -0.853694 2.00025)
			(stroke
				(width 0.0127)
				(type default)
			)
			(layer "F.SilkS")
		)
		(fp_line
			(start -1.118108 1.990852)
			(end -0.863346 1.990852)
			(stroke
				(width 0.0127)
				(type default)
			)
			(layer "F.SilkS")
		)
		(fp_line
			(start -1.108456 1.9812)
			(end -0.872744 1.9812)
			(stroke
				(width 0.0127)
				(type default)
			)
			(layer "F.SilkS")
		)
		(fp_line
			(start -1.099058 1.971802)
			(end -0.882396 1.971802)
			(stroke
				(width 0.0127)
				(type default)
			)
			(layer "F.SilkS")
		)
		(fp_line
			(start -1.089406 1.96215)
			(end -0.891794 1.96215)
			(stroke
				(width 0.0127)
				(type default)
			)
			(layer "F.SilkS")
		)
		(fp_line
			(start -1.080008 1.952752)
			(end -0.901446 1.952752)
			(stroke
				(width 0.0127)
				(type default)
			)
			(layer "F.SilkS")
		)
		(fp_line
			(start -1.070356 1.9431)
			(end -0.910844 1.9431)
			(stroke
				(width 0.0127)
				(type default)
			)
			(layer "F.SilkS")
		)
		(fp_line
			(start -1.060958 1.933702)
			(end -0.920496 1.933702)
			(stroke
				(width 0.0127)
				(type default)
			)
			(layer "F.SilkS")
		)
		(fp_line
			(start -1.051306 1.92405)
			(end -0.929894 1.92405)
			(stroke
				(width 0.0127)
				(type default)
			)
			(layer "F.SilkS")
		)
		(fp_line
			(start -1.041908 1.914652)
			(end -0.939546 1.914652)
			(stroke
				(width 0.0127)
				(type default)
			)
			(layer "F.SilkS")
		)
		(fp_line
			(start -1.032256 1.905)
			(end -0.948944 1.905)
			(stroke
				(width 0.0127)
				(type default)
			)
			(layer "F.SilkS")
		)
		(fp_line
			(start -1.022858 1.895602)
			(end -0.958596 1.895602)
			(stroke
				(width 0.0127)
				(type default)
			)
			(layer "F.SilkS")
		)
		(fp_line
			(start -1.013206 1.88595)
			(end -0.967994 1.88595)
			(stroke
				(width 0.0127)
				(type default)
			)
			(layer "F.SilkS")
		)
		(fp_line
			(start -1.003808 1.876552)
			(end -0.977646 1.876552)
			(stroke
				(width 0.0127)
				(type default)
			)
			(layer "F.SilkS")
		)
		(fp_line
			(start -0.994156 1.8669)
			(end -0.987044 1.8669)
			(stroke
				(width 0.0127)
				(type default)
			)
			(layer "F.SilkS")
		)
		(fp_line
			(start -0.9906 1.86309)
			(end -0.701294 2.15265)
			(stroke
				(width 0.0127)
				(type default)
			)
			(layer "F.SilkS")
		)
		(fp_line
			(start -0.719074 2.145538)
			(end -1.265936 2.14122)
			(stroke
				(width 0.0127)
				(type default)
			)
			(layer "F.SilkS")
		)
		(fp_line
			(start -0.71628 2.15265)
			(end -1.26492 2.15265)
			(stroke
				(width 0.0127)
				(type default)
			)
			(layer "F.SilkS")
		)
		(fp_line
			(start -0.635 1.8796)
			(end -1.7526 1.8796)
			(stroke
				(width 0.3302)
				(type default)
			)
			(layer "F.SilkS")
		)
		(fp_line
			(start 1.651 -1.778)
			(end -1.651 -1.778)
			(stroke
				(width 0.1524)
				(type default)
			)
			(layer "F.SilkS")
		)
		(fp_line
			(start 1.651 1.778)
			(end 1.651 -1.778)
			(stroke
				(width 0.1524)
				(type default)
			)
			(layer "F.SilkS")
		)
		(fp_poly
			(pts
				(xy -1.285748 2.159) (xy -1.285748 1.8796) (xy -1.778 1.8796) (xy -1.778 -1.8796) (xy 1.778 -1.8796)
				(xy 1.778 1.8796) (xy -0.694944 1.8796) (xy -0.694944 2.159)
			)
			(stroke
				(width 0)
				(type default)
			)
			(fill no)
			(layer "F.CrtYd")
		)
		(fp_poly
			(pts
				(xy -1.285748 2.159) (xy -1.285748 1.8796) (xy -1.778 1.8796) (xy -1.778 -1.8796) (xy 1.778 -1.8796)
				(xy 1.778 1.8796) (xy -0.694944 1.8796) (xy -0.694944 2.159)
			)
			(stroke
				(width 0)
				(type default)
			)
			(fill no)
			(layer "F.Fab")
		)
		(pad "1" smd rect
			(at -0.98425 0.9525)
			(size 0.762 1.143)
			(layers "F.Cu" "F.Mask" "F.Paste")
			(net "ADM1276_LATCH#")
		)
		(pad "2" smd rect
			(at 0.98425 0.9525)
			(size 0.762 1.143)
			(layers "F.Cu" "F.Mask" "F.Paste")
			(net "GND")
		)
		(pad "3" smd rect
			(at 0 -0.9525)
			(size 0.762 1.143)
			(layers "F.Cu" "F.Mask" "F.Paste")
			(net "TEMP_ALM#_REVERSE")
		)
	)
	(footprint ""
		(layer "F.Cu")
		(at 32.424624 -175.80991 90)
		(property "Reference" "R19"
			(at 0 0 90)
			(layer "F.SilkS")
			(hide yes)
			(effects
				(font
					(size 1.27 1.27)
				)
			)
		)
		(property "Value" "100KR2F-L1-GP"
			(at 0.064008 -3.993896 90)
			(unlocked yes)
			(layer "F.Fab")
			(hide yes)
			(effects
				(font
					(size 1.016 1.016)
					(thickness 0.1524)
				)
			)
		)
		(property "Device Type" "R402H16"
			(at 0.064008 -5.517896 90)
			(unlocked yes)
			(layer "F.Fab")
			(hide yes)
			(effects
				(font
					(size 1.016 1.016)
					(thickness 0.1524)
				)
			)
		)
		(duplicate_pad_numbers_are_jumpers no)
		(fp_line
			(start 0.508 -0.9398)
			(end -0.508 -0.9398)
			(stroke
				(width 0.1524)
				(type default)
			)
			(layer "F.SilkS")
		)
		(fp_line
			(start -0.508 -0.9398)
			(end -0.508 0.9398)
			(stroke
				(width 0.1524)
				(type default)
			)
			(layer "F.SilkS")
		)
		(fp_rect
			(start -0.508 0.9398)
			(end 0.508 -0.9398)
			(stroke
				(width 0)
				(type default)
			)
			(fill no)
			(layer "F.CrtYd")
		)
		(fp_rect
			(start -0.508 0.9398)
			(end 0.508 -0.9398)
			(stroke
				(width 0)
				(type default)
			)
			(fill no)
			(layer "F.Fab")
		)
		(pad "1" smd custom
			(at 0 -0.4445 90)
			(size 0.1397 0.1397)
			(layers "F.Cu" "F.Mask" "F.Paste")
			(net "PWM_EXP_2A")
			(options
				(clearance outline)
				(anchor circle)
			)
			(primitives
				(gr_poly
					(pts
						(arc
							(start -0.1778 -0.2794)
							(mid -0.249642 -0.249642)
							(end -0.2794 -0.1778)
						)
						(arc
							(start -0.2794 0.1778)
							(mid -0.249642 0.249642)
							(end -0.1778 0.2794)
						)
						(arc
							(start 0.1778 0.2794)
							(mid 0.249642 0.249642)
							(end 0.2794 0.1778)
						)
						(arc
							(start 0.2794 -0.1778)
							(mid 0.249642 -0.249642)
							(end 0.1778 -0.2794)
						)
					)
					(width 0)
					(fill yes)
				)
			)
		)
		(pad "2" smd custom
			(at 0 0.4445 90)
			(size 0.1397 0.1397)
			(layers "F.Cu" "F.Mask" "F.Paste")
			(net "GND")
			(options
				(clearance outline)
				(anchor circle)
			)
			(primitives
				(gr_poly
					(pts
						(arc
							(start -0.1778 -0.2794)
							(mid -0.249642 -0.249642)
							(end -0.2794 -0.1778)
						)
						(arc
							(start -0.2794 0.1778)
							(mid -0.249642 0.249642)
							(end -0.1778 0.2794)
						)
						(arc
							(start 0.1778 0.2794)
							(mid 0.249642 0.249642)
							(end 0.2794 0.1778)
						)
						(arc
							(start 0.2794 -0.1778)
							(mid 0.249642 -0.249642)
							(end 0.1778 -0.2794)
						)
					)
					(width 0)
					(fill yes)
				)
			)
		)
	)
	(footprint ""
		(layer "F.Cu")
		(at 43.8658 -382.9558 -90)
		(property "Reference" "D14"
			(at 0 0 270)
			(layer "F.SilkS")
			(hide yes)
			(effects
				(font
					(size 1.27 1.27)
				)
			)
		)
		(property "Value" "MBRS340T3G-GP"
			(at 0 -10.6172 270)
			(unlocked yes)
			(layer "F.Fab")
			(hide yes)
			(effects
				(font
					(size 1.016 1.016)
					(thickness 0.1524)
				)
			)
		)
		(property "Device Type" "D8059AKH101"
			(at 0 -12.1412 270)
			(unlocked yes)
			(layer "F.Fab")
			(hide yes)
			(effects
				(font
					(size 1.016 1.016)
					(thickness 0.1524)
				)
			)
		)
		(duplicate_pad_numbers_are_jumpers no)
		(fp_line
			(start 3.175 5.2832)
			(end -3.175 5.2832)
			(stroke
				(width 0.508)
				(type default)
			)
			(layer "F.SilkS")
		)
		(fp_line
			(start -3.175 5.1054)
			(end -3.175 -5.1054)
			(stroke
				(width 0.1524)
				(type default)
			)
			(layer "F.SilkS")
		)
		(fp_line
			(start 3.175 5.1054)
			(end -3.175 5.1054)
			(stroke
				(width 0.1524)
				(type default)
			)
			(layer "F.SilkS")
		)
		(fp_line
			(start -3.175 -5.1054)
			(end 3.175 -5.1054)
			(stroke
				(width 0.1524)
				(type default)
			)
			(layer "F.SilkS")
		)
		(fp_line
			(start 3.175 -5.1054)
			(end 3.175 5.1054)
			(stroke
				(width 0.1524)
				(type default)
			)
			(layer "F.SilkS")
		)
		(fp_rect
			(start -3.429 5.1816)
			(end 3.429 -5.1816)
			(stroke
				(width 0)
				(type default)
			)
			(fill no)
			(layer "F.CrtYd")
		)
		(fp_poly
			(pts
				(xy -3.429 -5.1816) (xy 3.429 -5.1816) (xy 3.429 5.1816) (xy -3.429 5.1816)
			)
			(stroke
				(width 0)
				(type default)
			)
			(fill no)
			(layer "F.Fab")
		)
		(pad "A" smd rect
			(at 0 -3.77571 270)
			(size 3.2512 2.159)
			(layers "F.Cu" "F.Mask" "F.Paste")
			(net "GND")
		)
		(pad "K" smd rect
			(at 0 3.77571 270)
			(size 3.2512 2.159)
			(layers "F.Cu" "F.Mask" "F.Paste")
			(net "P12V")
		)
	)
	(footprint ""
		(layer "F.Cu")
		(at 19.1008 -187.8838)
		(property "Reference" "C37"
			(at 0 0 0)
			(layer "F.SilkS")
			(hide yes)
			(effects
				(font
					(size 1.27 1.27)
				)
			)
		)
		(property "Value" "SCD1U16V2KX-3GP"
			(at 1.1811 -2.7051 0)
			(unlocked yes)
			(layer "F.Fab")
			(hide yes)
			(effects
				(font
					(size 1.016 1.016)
					(thickness 0.1524)
				)
			)
		)
		(property "Device Type" "C402H22"
			(at 1.1811 -4.2291 0)
			(unlocked yes)
			(layer "F.Fab")
			(hide yes)
			(effects
				(font
					(size 1.016 1.016)
					(thickness 0.1524)
				)
			)
		)
		(duplicate_pad_numbers_are_jumpers no)
		(fp_rect
			(start -0.4318 0.9525)
			(end 0.4318 -0.9525)
			(stroke
				(width 0)
				(type default)
			)
			(fill no)
			(layer "F.CrtYd")
		)
		(fp_rect
			(start -0.4318 0.9525)
			(end 0.4318 -0.9525)
			(stroke
				(width 0)
				(type default)
			)
			(fill no)
			(layer "F.Fab")
		)
		(pad "1" smd custom
			(at 0 -0.4445)
			(size 0.1524 0.1524)
			(layers "F.Cu" "F.Mask" "F.Paste")
			(net "FAN_TACH8")
			(options
				(clearance outline)
				(anchor circle)
			)
			(primitives
				(gr_poly
					(pts
						(arc
							(start 0.3048 -0.2032)
							(mid 0.275042 -0.275042)
							(end 0.2032 -0.3048)
						)
						(arc
							(start -0.2032 -0.3048)
							(mid -0.275042 -0.275042)
							(end -0.3048 -0.2032)
						)
						(arc
							(start -0.3048 0.2032)
							(mid -0.275042 0.275042)
							(end -0.2032 0.3048)
						)
						(arc
							(start 0.2032 0.3048)
							(mid 0.275042 0.275042)
							(end 0.3048 0.2032)
						)
					)
					(width 0)
					(fill yes)
				)
			)
		)
		(pad "2" smd custom
			(at 0 0.4445)
			(size 0.1524 0.1524)
			(layers "F.Cu" "F.Mask" "F.Paste")
			(net "GND")
			(options
				(clearance outline)
				(anchor circle)
			)
			(primitives
				(gr_poly
					(pts
						(arc
							(start 0.3048 -0.2032)
							(mid 0.275042 -0.275042)
							(end 0.2032 -0.3048)
						)
						(arc
							(start -0.2032 -0.3048)
							(mid -0.275042 -0.275042)
							(end -0.3048 -0.2032)
						)
						(arc
							(start -0.3048 0.2032)
							(mid -0.275042 0.275042)
							(end -0.2032 0.3048)
						)
						(arc
							(start 0.2032 0.3048)
							(mid 0.275042 0.275042)
							(end 0.3048 0.2032)
						)
					)
					(width 0)
					(fill yes)
				)
			)
		)
	)
	(footprint ""
		(layer "F.Cu")
		(at 22.352 -186.2836 -90)
		(property "Reference" "R81"
			(at 0 0 270)
			(layer "F.SilkS")
			(hide yes)
			(effects
				(font
					(size 1.27 1.27)
				)
			)
		)
		(property "Value" "4K7R2F-GP"
			(at 0.064008 -3.993896 270)
			(unlocked yes)
			(layer "F.Fab")
			(hide yes)
			(effects
				(font
					(size 1.016 1.016)
					(thickness 0.1524)
				)
			)
		)
		(property "Device Type" "R402H16"
			(at 0.064008 -5.517896 270)
			(unlocked yes)
			(layer "F.Fab")
			(hide yes)
			(effects
				(font
					(size 1.016 1.016)
					(thickness 0.1524)
				)
			)
		)
		(duplicate_pad_numbers_are_jumpers no)
		(fp_line
			(start -0.508 -0.9398)
			(end -0.508 0.9398)
			(stroke
				(width 0.1524)
				(type default)
			)
			(layer "F.SilkS")
		)
		(fp_line
			(start 0.508 -0.9398)
			(end -0.508 -0.9398)
			(stroke
				(width 0.1524)
				(type default)
			)
			(layer "F.SilkS")
		)
		(fp_rect
			(start -0.508 0.9398)
			(end 0.508 -0.9398)
			(stroke
				(width 0)
				(type default)
			)
			(fill no)
			(layer "F.CrtYd")
		)
		(fp_rect
			(start -0.508 0.9398)
			(end 0.508 -0.9398)
			(stroke
				(width 0)
				(type default)
			)
			(fill no)
			(layer "F.Fab")
		)
		(pad "1" smd custom
			(at 0 -0.4445 270)
			(size 0.1397 0.1397)
			(layers "F.Cu" "F.Mask" "F.Paste")
			(net "P12V")
			(options
				(clearance outline)
				(anchor circle)
			)
			(primitives
				(gr_poly
					(pts
						(arc
							(start -0.1778 -0.2794)
							(mid -0.249642 -0.249642)
							(end -0.2794 -0.1778)
						)
						(arc
							(start -0.2794 0.1778)
							(mid -0.249642 0.249642)
							(end -0.1778 0.2794)
						)
						(arc
							(start 0.1778 0.2794)
							(mid 0.249642 0.249642)
							(end 0.2794 0.1778)
						)
						(arc
							(start 0.2794 -0.1778)
							(mid 0.249642 -0.249642)
							(end 0.1778 -0.2794)
						)
					)
					(width 0)
					(fill yes)
				)
			)
		)
		(pad "2" smd custom
			(at 0 0.4445 270)
			(size 0.1397 0.1397)
			(layers "F.Cu" "F.Mask" "F.Paste")
			(net "FAN_TACH8")
			(options
				(clearance outline)
				(anchor circle)
			)
			(primitives
				(gr_poly
					(pts
						(arc
							(start -0.1778 -0.2794)
							(mid -0.249642 -0.249642)
							(end -0.2794 -0.1778)
						)
						(arc
							(start -0.2794 0.1778)
							(mid -0.249642 0.249642)
							(end -0.1778 0.2794)
						)
						(arc
							(start 0.1778 0.2794)
							(mid 0.249642 0.249642)
							(end 0.2794 0.1778)
						)
						(arc
							(start 0.2794 -0.1778)
							(mid 0.249642 -0.249642)
							(end 0.1778 -0.2794)
						)
					)
					(width 0)
					(fill yes)
				)
			)
		)
	)
	(footprint ""
		(layer "F.Cu")
		(at 23.622 -363.601 -90)
		(property "Reference" "PC5"
			(at 0 0 270)
			(layer "F.SilkS")
			(hide yes)
			(effects
				(font
					(size 1.27 1.27)
				)
			)
		)
		(property "Value" "SCD01U25V2KX-3GP"
			(at 1.1811 -2.7051 270)
			(unlocked yes)
			(layer "F.Fab")
			(hide yes)
			(effects
				(font
					(size 1.016 1.016)
					(thickness 0.1524)
				)
			)
		)
		(property "Device Type" "C402H22"
			(at 1.1811 -4.2291 270)
			(unlocked yes)
			(layer "F.Fab")
			(hide yes)
			(effects
				(font
					(size 1.016 1.016)
					(thickness 0.1524)
				)
			)
		)
		(duplicate_pad_numbers_are_jumpers no)
		(fp_rect
			(start -0.4318 0.9525)
			(end 0.4318 -0.9525)
			(stroke
				(width 0)
				(type default)
			)
			(fill no)
			(layer "F.CrtYd")
		)
		(fp_rect
			(start -0.4318 0.9525)
			(end 0.4318 -0.9525)
			(stroke
				(width 0)
				(type default)
			)
			(fill no)
			(layer "F.Fab")
		)
		(pad "1" smd custom
			(at 0 -0.4445 270)
			(size 0.1524 0.1524)
			(layers "F.Cu" "F.Mask" "F.Paste")
			(net "ADM1276_TIMER")
			(options
				(clearance outline)
				(anchor circle)
			)
			(primitives
				(gr_poly
					(pts
						(arc
							(start 0.3048 -0.2032)
							(mid 0.275042 -0.275042)
							(end 0.2032 -0.3048)
						)
						(arc
							(start -0.2032 -0.3048)
							(mid -0.275042 -0.275042)
							(end -0.3048 -0.2032)
						)
						(arc
							(start -0.3048 0.2032)
							(mid -0.275042 0.275042)
							(end -0.2032 0.3048)
						)
						(arc
							(start 0.2032 0.3048)
							(mid 0.275042 0.275042)
							(end 0.3048 0.2032)
						)
					)
					(width 0)
					(fill yes)
				)
			)
		)
		(pad "2" smd custom
			(at 0 0.4445 270)
			(size 0.1524 0.1524)
			(layers "F.Cu" "F.Mask" "F.Paste")
			(net "GND")
			(options
				(clearance outline)
				(anchor circle)
			)
			(primitives
				(gr_poly
					(pts
						(arc
							(start 0.3048 -0.2032)
							(mid 0.275042 -0.275042)
							(end 0.2032 -0.3048)
						)
						(arc
							(start -0.2032 -0.3048)
							(mid -0.275042 -0.275042)
							(end -0.3048 -0.2032)
						)
						(arc
							(start -0.3048 0.2032)
							(mid -0.275042 0.275042)
							(end -0.2032 0.3048)
						)
						(arc
							(start 0.2032 0.3048)
							(mid 0.275042 0.275042)
							(end 0.3048 0.2032)
						)
					)
					(width 0)
					(fill yes)
				)
			)
		)
	)
)
